(kicad_pcb
	(version 20260206)
	(generator "pcbnew")
	(generator_version "10.0")
	(general
		(thickness 1.6)
		(legacy_teardrops no)
	)
	(paper "A4")
	(title_block
		(title "Bryce Canyon_F.DPB_16315-1-OCP.brd")
		(comment 1 "Bryce Canyon / footprints 218-225 of 2223")
	)
	(layers
		(0 "F.Cu" signal "TOP")
		(4 "In1.Cu" signal "L2GND")
		(6 "In2.Cu" signal "L3")
		(8 "In3.Cu" signal "L4GND")
		(10 "In4.Cu" signal "L5")
		(12 "In5.Cu" signal "L6VCC")
		(14 "In6.Cu" signal "L7VCC")
		(16 "In7.Cu" signal "L8")
		(18 "In8.Cu" signal "L9GND")
		(20 "In9.Cu" signal "L10")
		(22 "In10.Cu" signal "L11GND")
		(2 "B.Cu" signal "BOTTOM")
		(9 "F.Adhes" user "F.Adhesive")
		(11 "B.Adhes" user "B.Adhesive")
		(13 "F.Paste" user "Package Geometry/Pastemask Top")
		(15 "B.Paste" user "Package Geometry/Pastemask Bottom")
		(5 "F.SilkS" user "Ref Des/Silkscreen Top")
		(7 "B.SilkS" user "Ref Des/Silkscreen Bottom")
		(1 "F.Mask" user "Board Geometry/Soldermask Top")
		(3 "B.Mask" user "Board Geometry/Soldermask Bottom")
		(17 "Dwgs.User" user "User.Drawings")
		(19 "Cmts.User" user "User.Comments")
		(21 "Eco1.User" user "User.Eco1")
		(23 "Eco2.User" user "User.Eco2")
		(25 "Edge.Cuts" user "Board Geometry/Outline")
		(27 "Margin" user)
		(31 "F.CrtYd" user "Package Geometry/Place Bound Top")
		(29 "B.CrtYd" user "Package Geometry/Place Bound Bottom")
		(35 "F.Fab" user "Ref Des/Assembly Top")
		(33 "B.Fab" user "Ref Des/Assembly Bottom")
	)
	(footprint ""
		(layer "F.Cu")
		(at 342.955626 -127.767334 180)
		(property "Reference" "Q246"
			(at 0 0 180)
			(layer "F.SilkS")
			(hide yes)
			(effects
				(font
					(size 1.27 1.27)
				)
			)
		)
		(property "Value" "2N7002K-2-GP"
			(at 0.127 -8.9662 180)
			(unlocked yes)
			(layer "F.Fab")
			(hide yes)
			(effects
				(font
					(size 1.016 1.016)
					(thickness 0.1524)
				)
			)
		)
		(property "Device Type" "SOT23DGS2D4H44"
			(at 0.127 -10.4902 180)
			(unlocked yes)
			(layer "F.Fab")
			(hide yes)
			(effects
				(font
					(size 1.016 1.016)
					(thickness 0.1524)
				)
			)
		)
		(duplicate_pad_numbers_are_jumpers no)
		(fp_line
			(start 1.651 1.778)
			(end 1.651 -1.778)
			(stroke
				(width 0.1524)
				(type default)
			)
			(layer "F.SilkS")
		)
		(fp_line
			(start 1.651 -1.778)
			(end -1.651 -1.778)
			(stroke
				(width 0.1524)
				(type default)
			)
			(layer "F.SilkS")
		)
		(fp_line
			(start -1.651 1.778)
			(end 1.651 1.778)
			(stroke
				(width 0.1524)
				(type default)
			)
			(layer "F.SilkS")
		)
		(fp_line
			(start -1.651 -1.778)
			(end -1.651 1.778)
			(stroke
				(width 0.1524)
				(type default)
			)
			(layer "F.SilkS")
		)
		(fp_poly
			(pts
				(xy -1.778 1.8796) (xy -1.778 -1.8796) (xy 1.778 -1.8796) (xy 1.778 1.8796)
			)
			(stroke
				(width 0)
				(type default)
			)
			(fill no)
			(layer "F.CrtYd")
		)
		(fp_poly
			(pts
				(xy -1.778 1.8796) (xy -1.778 -1.8796) (xy 1.778 -1.8796) (xy 1.778 1.8796)
			)
			(stroke
				(width 0)
				(type default)
			)
			(fill no)
			(layer "F.Fab")
		)
		(pad "D" smd custom
			(at 0 -0.9525 180)
			(size 0.1905 0.1905)
			(layers "F.Cu" "F.Mask" "F.Paste")
			(net "FLT_HDD19_N")
			(options
				(clearance outline)
				(anchor circle)
			)
			(primitives
				(gr_poly
					(pts
						(arc
							(start -0.1778 0.5715)
							(mid -0.321484 0.511984)
							(end -0.381 0.3683)
						)
						(arc
							(start -0.381 -0.3683)
							(mid -0.321484 -0.511984)
							(end -0.1778 -0.5715)
						)
						(arc
							(start 0.1778 -0.5715)
							(mid 0.321484 -0.511984)
							(end 0.381 -0.3683)
						)
						(arc
							(start 0.381 0.3683)
							(mid 0.321484 0.511984)
							(end 0.1778 0.5715)
						)
					)
					(width 0)
					(fill yes)
				)
			)
		)
		(pad "G" smd custom
			(at -0.98425 0.9525 180)
			(size 0.1905 0.1905)
			(layers "F.Cu" "F.Mask" "F.Paste")
			(net "DRIVE_A_19_FLT_LED")
			(options
				(clearance outline)
				(anchor circle)
			)
			(primitives
				(gr_poly
					(pts
						(arc
							(start -0.1778 0.5715)
							(mid -0.321484 0.511984)
							(end -0.381 0.3683)
						)
						(arc
							(start -0.381 -0.3683)
							(mid -0.321484 -0.511984)
							(end -0.1778 -0.5715)
						)
						(arc
							(start 0.1778 -0.5715)
							(mid 0.321484 -0.511984)
							(end 0.381 -0.3683)
						)
						(arc
							(start 0.381 0.3683)
							(mid 0.321484 0.511984)
							(end 0.1778 0.5715)
						)
					)
					(width 0)
					(fill yes)
				)
			)
		)
		(pad "S" smd custom
			(at 0.98425 0.9525 180)
			(size 0.1905 0.1905)
			(layers "F.Cu" "F.Mask" "F.Paste")
			(net "GND")
			(options
				(clearance outline)
				(anchor circle)
			)
			(primitives
				(gr_poly
					(pts
						(arc
							(start -0.1778 0.5715)
							(mid -0.321484 0.511984)
							(end -0.381 0.3683)
						)
						(arc
							(start -0.381 -0.3683)
							(mid -0.321484 -0.511984)
							(end -0.1778 -0.5715)
						)
						(arc
							(start 0.1778 -0.5715)
							(mid 0.321484 -0.511984)
							(end 0.381 -0.3683)
						)
						(arc
							(start 0.381 0.3683)
							(mid 0.321484 0.511984)
							(end 0.1778 0.5715)
						)
					)
					(width 0)
					(fill yes)
				)
			)
		)
	)
	(footprint ""
		(layer "F.Cu")
		(at 266.991338 -150.47341)
		(property "Reference" "TP189"
			(at 0 0 0)
			(layer "F.SilkS")
			(hide yes)
			(effects
				(font
					(size 1.27 1.27)
				)
			)
		)
		(property "Value" "TPAD32-GP"
			(at -0.0508 -1.6764 0)
			(unlocked yes)
			(layer "F.Fab")
			(hide yes)
			(effects
				(font
					(size 1.016 1.016)
					(thickness 0.1524)
				)
			)
		)
		(property "Device Type" "TPAD32"
			(at -0.0508 -3.2004 0)
			(unlocked yes)
			(layer "F.Fab")
			(hide yes)
			(effects
				(font
					(size 1.016 1.016)
					(thickness 0.1524)
				)
			)
		)
		(duplicate_pad_numbers_are_jumpers no)
		(fp_poly
			(pts
				(arc
					(start 0.4064 0)
					(mid -0.4064 0)
					(end 0.4064 0)
				)
			)
			(stroke
				(width 0)
				(type default)
			)
			(fill no)
			(layer "F.CrtYd")
		)
		(fp_poly
			(pts
				(arc
					(start 0.7112 0)
					(mid -0.7112 0)
					(end 0.7112 0)
				)
			)
			(stroke
				(width 0)
				(type default)
			)
			(fill no)
			(layer "F.Fab")
		)
		(pad "1" smd circle
			(at 0 0)
			(size 0.8128 0.8128)
			(layers "F.Cu" "F.Mask" "F.Paste")
			(net "TP_COMP_B_KR_P0_TX_DP")
		)
	)
	(footprint ""
		(layer "F.Cu")
		(at 22.996398 -48.554894 90)
		(property "Reference" "R695"
			(at 0 0 90)
			(layer "F.SilkS")
			(hide yes)
			(effects
				(font
					(size 1.27 1.27)
				)
			)
		)
		(property "Value" "4K7R2J-2-GP"
			(at 0.064008 -3.993896 90)
			(unlocked yes)
			(layer "F.Fab")
			(hide yes)
			(effects
				(font
					(size 1.016 1.016)
					(thickness 0.1524)
				)
			)
		)
		(property "Device Type" "R402H16"
			(at 0.064008 -5.517896 90)
			(unlocked yes)
			(layer "F.Fab")
			(hide yes)
			(effects
				(font
					(size 1.016 1.016)
					(thickness 0.1524)
				)
			)
		)
		(duplicate_pad_numbers_are_jumpers no)
		(fp_line
			(start 0.508 -0.9398)
			(end -0.508 -0.9398)
			(stroke
				(width 0.1524)
				(type default)
			)
			(layer "F.SilkS")
		)
		(fp_line
			(start -0.508 -0.9398)
			(end -0.508 0.9398)
			(stroke
				(width 0.1524)
				(type default)
			)
			(layer "F.SilkS")
		)
		(fp_rect
			(start -0.508 0.9398)
			(end 0.508 -0.9398)
			(stroke
				(width 0)
				(type default)
			)
			(fill no)
			(layer "F.CrtYd")
		)
		(fp_rect
			(start -0.508 0.9398)
			(end 0.508 -0.9398)
			(stroke
				(width 0)
				(type default)
			)
			(fill no)
			(layer "F.Fab")
		)
		(pad "1" smd custom
			(at 0 -0.4445 90)
			(size 0.1397 0.1397)
			(layers "F.Cu" "F.Mask" "F.Paste")
			(net "SW_PWR_R_HDD24")
			(options
				(clearance outline)
				(anchor circle)
			)
			(primitives
				(gr_poly
					(pts
						(arc
							(start -0.1778 -0.2794)
							(mid -0.249642 -0.249642)
							(end -0.2794 -0.1778)
						)
						(arc
							(start -0.2794 0.1778)
							(mid -0.249642 0.249642)
							(end -0.1778 0.2794)
						)
						(arc
							(start 0.1778 0.2794)
							(mid 0.249642 0.249642)
							(end 0.2794 0.1778)
						)
						(arc
							(start 0.2794 -0.1778)
							(mid 0.249642 -0.249642)
							(end 0.1778 -0.2794)
						)
					)
					(width 0)
					(fill yes)
				)
			)
		)
		(pad "2" smd custom
			(at 0 0.4445 90)
			(size 0.1397 0.1397)
			(layers "F.Cu" "F.Mask" "F.Paste")
			(net "GND")
			(options
				(clearance outline)
				(anchor circle)
			)
			(primitives
				(gr_poly
					(pts
						(arc
							(start -0.1778 -0.2794)
							(mid -0.249642 -0.249642)
							(end -0.2794 -0.1778)
						)
						(arc
							(start -0.2794 0.1778)
							(mid -0.249642 0.249642)
							(end -0.1778 0.2794)
						)
						(arc
							(start 0.1778 0.2794)
							(mid 0.249642 0.249642)
							(end 0.2794 0.1778)
						)
						(arc
							(start 0.2794 -0.1778)
							(mid 0.249642 -0.249642)
							(end 0.1778 -0.2794)
						)
					)
					(width 0)
					(fill yes)
				)
			)
		)
	)
	(footprint ""
		(layer "F.Cu")
		(at 281.2034 -280.1366)
		(property "Reference" "C37"
			(at 0 0 0)
			(layer "F.SilkS")
			(hide yes)
			(effects
				(font
					(size 1.27 1.27)
				)
			)
		)
		(property "Value" "SC1U16V3KX-5GP"
			(at 0 -2.8194 0)
			(unlocked yes)
			(layer "F.Fab")
			(hide yes)
			(effects
				(font
					(size 1.016 1.016)
					(thickness 0.1524)
				)
			)
		)
		(property "Device Type" "C603H36"
			(at 0 -4.3434 0)
			(unlocked yes)
			(layer "F.Fab")
			(hide yes)
			(effects
				(font
					(size 1.016 1.016)
					(thickness 0.1524)
				)
			)
		)
		(duplicate_pad_numbers_are_jumpers no)
		(fp_line
			(start 0.508 0)
			(end -0.508 0)
			(stroke
				(width 0.2032)
				(type default)
			)
			(layer "F.SilkS")
		)
		(fp_rect
			(start -0.5842 1.3335)
			(end 0.5842 -1.3335)
			(stroke
				(width 0)
				(type default)
			)
			(fill no)
			(layer "F.CrtYd")
		)
		(fp_rect
			(start -0.5842 1.3335)
			(end 0.5842 -1.3335)
			(stroke
				(width 0)
				(type default)
			)
			(fill no)
			(layer "F.Fab")
		)
		(pad "1" smd custom
			(at 0 -0.762)
			(size 0.2159 0.2159)
			(layers "F.Cu" "F.Mask" "F.Paste")
			(net "P3V3_STBY_A")
			(options
				(clearance outline)
				(anchor circle)
			)
			(primitives
				(gr_poly
					(pts
						(arc
							(start -0.3302 -0.4318)
							(mid -0.402042 -0.402042)
							(end -0.4318 -0.3302)
						)
						(arc
							(start -0.4318 0.3302)
							(mid -0.402042 0.402042)
							(end -0.3302 0.4318)
						)
						(arc
							(start 0.3302 0.4318)
							(mid 0.402042 0.402042)
							(end 0.4318 0.3302)
						)
						(arc
							(start 0.4318 -0.3302)
							(mid 0.402042 -0.402042)
							(end 0.3302 -0.4318)
						)
					)
					(width 0)
					(fill yes)
				)
			)
		)
		(pad "2" smd custom
			(at 0 0.762)
			(size 0.2159 0.2159)
			(layers "F.Cu" "F.Mask" "F.Paste")
			(net "GND")
			(options
				(clearance outline)
				(anchor circle)
			)
			(primitives
				(gr_poly
					(pts
						(arc
							(start -0.3302 -0.4318)
							(mid -0.402042 -0.402042)
							(end -0.4318 -0.3302)
						)
						(arc
							(start -0.4318 0.3302)
							(mid -0.402042 0.402042)
							(end -0.3302 0.4318)
						)
						(arc
							(start 0.3302 0.4318)
							(mid 0.402042 0.402042)
							(end 0.4318 0.3302)
						)
						(arc
							(start 0.4318 -0.3302)
							(mid 0.402042 -0.402042)
							(end 0.3302 -0.4318)
						)
					)
					(width 0)
					(fill yes)
				)
			)
		)
	)
	(footprint ""
		(layer "F.Cu")
		(at 272.542 -309.105046 180)
		(property "Reference" "VIA63"
			(at 0 0 180)
			(layer "F.SilkS")
			(hide yes)
			(effects
				(font
					(size 1.27 1.27)
				)
			)
		)
		(property "Value" "100OHM-8L-1D6MM-L18L16-GP"
			(at -3.7211 -4.5085 180)
			(unlocked yes)
			(layer "F.Fab")
			(hide yes)
			(effects
				(font
					(size 1.016 1.016)
					(thickness 0.1524)
				)
			)
		)
		(property "Device Type" "VIA-PCIE-4P-394076"
			(at -3.7211 -6.0325 180)
			(unlocked yes)
			(layer "F.Fab")
			(hide yes)
			(effects
				(font
					(size 1.016 1.016)
					(thickness 0.1524)
				)
			)
		)
		(duplicate_pad_numbers_are_jumpers no)
		(fp_rect
			(start -1.9685 0.381)
			(end 1.9685 -0.381)
			(stroke
				(width 0)
				(type default)
			)
			(fill no)
			(layer "F.CrtYd")
		)
		(fp_rect
			(start -1.9685 0.381)
			(end 1.9685 -0.381)
			(stroke
				(width 0)
				(type default)
			)
			(fill no)
			(layer "F.Fab")
		)
		(pad "1" thru_hole circle
			(at -1.5875 0 180)
			(size 0.508 0.508)
			(drill 0.254)
			(layers "*.Cu" "*.Mask")
			(remove_unused_layers no)
			(net "GND")
			(clearance 0.127)
			(thermal_gap 0.127)
		)
		(pad "2" thru_hole circle
			(at -0.5715 0 180)
			(size 0.508 0.508)
			(drill 0.254)
			(layers "*.Cu" "*.Mask")
			(remove_unused_layers no)
			(net "PHY_SCC_A_TO_DRV_A_28_DP")
			(clearance 0.127)
			(thermal_gap 0.127)
		)
		(pad "3" thru_hole circle
			(at 0.5715 0 180)
			(size 0.508 0.508)
			(drill 0.254)
			(layers "*.Cu" "*.Mask")
			(remove_unused_layers no)
			(net "PHY_SCC_A_TO_DRV_A_28_DN")
			(clearance 0.127)
			(thermal_gap 0.127)
		)
		(pad "4" thru_hole circle
			(at 1.5875 0 180)
			(size 0.508 0.508)
			(drill 0.254)
			(layers "*.Cu" "*.Mask")
			(remove_unused_layers no)
			(net "GND")
			(clearance 0.127)
			(thermal_gap 0.127)
		)
	)
	(footprint ""
		(layer "F.Cu")
		(at 174.498 -282.034742 -90)
		(property "Reference" "C113"
			(at 0 0 270)
			(layer "F.SilkS")
			(hide yes)
			(effects
				(font
					(size 1.27 1.27)
				)
			)
		)
		(property "Value" "SCD033U25V2KX-GP"
			(at 1.1811 -2.7051 270)
			(unlocked yes)
			(layer "F.Fab")
			(hide yes)
			(effects
				(font
					(size 1.016 1.016)
					(thickness 0.1524)
				)
			)
		)
		(property "Device Type" "C402H22"
			(at 1.1811 -4.2291 270)
			(unlocked yes)
			(layer "F.Fab")
			(hide yes)
			(effects
				(font
					(size 1.016 1.016)
					(thickness 0.1524)
				)
			)
		)
		(duplicate_pad_numbers_are_jumpers no)
		(fp_rect
			(start -0.4318 0.9525)
			(end 0.4318 -0.9525)
			(stroke
				(width 0)
				(type default)
			)
			(fill no)
			(layer "F.CrtYd")
		)
		(fp_rect
			(start -0.4318 0.9525)
			(end 0.4318 -0.9525)
			(stroke
				(width 0)
				(type default)
			)
			(fill no)
			(layer "F.Fab")
		)
		(pad "1" smd custom
			(at 0 -0.4445 270)
			(size 0.1524 0.1524)
			(layers "F.Cu" "F.Mask" "F.Paste")
			(net "SW_HDD_P5")
			(options
				(clearance outline)
				(anchor circle)
			)
			(primitives
				(gr_poly
					(pts
						(arc
							(start 0.3048 -0.2032)
							(mid 0.275042 -0.275042)
							(end 0.2032 -0.3048)
						)
						(arc
							(start -0.2032 -0.3048)
							(mid -0.275042 -0.275042)
							(end -0.3048 -0.2032)
						)
						(arc
							(start -0.3048 0.2032)
							(mid -0.275042 0.275042)
							(end -0.2032 0.3048)
						)
						(arc
							(start 0.2032 0.3048)
							(mid 0.275042 0.275042)
							(end 0.3048 0.2032)
						)
					)
					(width 0)
					(fill yes)
				)
			)
		)
		(pad "2" smd custom
			(at 0 0.4445 270)
			(size 0.1524 0.1524)
			(layers "F.Cu" "F.Mask" "F.Paste")
			(net "GND")
			(options
				(clearance outline)
				(anchor circle)
			)
			(primitives
				(gr_poly
					(pts
						(arc
							(start 0.3048 -0.2032)
							(mid 0.275042 -0.275042)
							(end 0.2032 -0.3048)
						)
						(arc
							(start -0.2032 -0.3048)
							(mid -0.275042 -0.275042)
							(end -0.3048 -0.2032)
						)
						(arc
							(start -0.3048 0.2032)
							(mid -0.275042 0.275042)
							(end -0.2032 0.3048)
						)
						(arc
							(start 0.2032 0.3048)
							(mid 0.275042 0.275042)
							(end 0.3048 0.2032)
						)
					)
					(width 0)
					(fill yes)
				)
			)
		)
	)
	(footprint ""
		(layer "F.Cu")
		(at 401.80895 -172.851318 90)
		(property "Reference" "C309"
			(at 0 0 90)
			(layer "F.SilkS")
			(hide yes)
			(effects
				(font
					(size 1.27 1.27)
				)
			)
		)
		(property "Value" "SCD033U25V2KX-GP"
			(at 1.1811 -2.7051 90)
			(unlocked yes)
			(layer "F.Fab")
			(hide yes)
			(effects
				(font
					(size 1.016 1.016)
					(thickness 0.1524)
				)
			)
		)
		(property "Device Type" "C402H22"
			(at 1.1811 -4.2291 90)
			(unlocked yes)
			(layer "F.Fab")
			(hide yes)
			(effects
				(font
					(size 1.016 1.016)
					(thickness 0.1524)
				)
			)
		)
		(duplicate_pad_numbers_are_jumpers no)
		(fp_rect
			(start -0.4318 0.9525)
			(end 0.4318 -0.9525)
			(stroke
				(width 0)
				(type default)
			)
			(fill no)
			(layer "F.CrtYd")
		)
		(fp_rect
			(start -0.4318 0.9525)
			(end 0.4318 -0.9525)
			(stroke
				(width 0)
				(type default)
			)
			(fill no)
			(layer "F.Fab")
		)
		(pad "1" smd custom
			(at 0 -0.4445 90)
			(size 0.1524 0.1524)
			(layers "F.Cu" "F.Mask" "F.Paste")
			(net "P12V_A")
			(options
				(clearance outline)
				(anchor circle)
			)
			(primitives
				(gr_poly
					(pts
						(arc
							(start 0.3048 -0.2032)
							(mid 0.275042 -0.275042)
							(end 0.2032 -0.3048)
						)
						(arc
							(start -0.2032 -0.3048)
							(mid -0.275042 -0.275042)
							(end -0.3048 -0.2032)
						)
						(arc
							(start -0.3048 0.2032)
							(mid -0.275042 0.275042)
							(end -0.2032 0.3048)
						)
						(arc
							(start 0.2032 0.3048)
							(mid 0.275042 0.275042)
							(end 0.3048 0.2032)
						)
					)
					(width 0)
					(fill yes)
				)
			)
		)
		(pad "2" smd custom
			(at 0 0.4445 90)
			(size 0.1524 0.1524)
			(layers "F.Cu" "F.Mask" "F.Paste")
			(net "SW_HDD_N20")
			(options
				(clearance outline)
				(anchor circle)
			)
			(primitives
				(gr_poly
					(pts
						(arc
							(start 0.3048 -0.2032)
							(mid 0.275042 -0.275042)
							(end 0.2032 -0.3048)
						)
						(arc
							(start -0.2032 -0.3048)
							(mid -0.275042 -0.275042)
							(end -0.3048 -0.2032)
						)
						(arc
							(start -0.3048 0.2032)
							(mid -0.275042 0.275042)
							(end -0.2032 0.3048)
						)
						(arc
							(start 0.2032 0.3048)
							(mid 0.275042 0.275042)
							(end 0.3048 0.2032)
						)
					)
					(width 0)
					(fill yes)
				)
			)
		)
	)
	(footprint ""
		(layer "F.Cu")
		(at 48.425354 -276.99589 180)
		(property "Reference" "D1"
			(at 0 0 180)
			(layer "F.SilkS")
			(hide yes)
			(effects
				(font
					(size 1.27 1.27)
				)
			)
		)
		(property "Value" "RB551V30-GP"
			(at 0 -6.7818 180)
			(unlocked yes)
			(layer "F.Fab")
			(hide yes)
			(effects
				(font
					(size 1.016 1.016)
					(thickness 0.1524)
				)
			)
		)
		(property "Device Type" "SOD323AKH38"
			(at 0 -8.6868 180)
			(unlocked yes)
			(layer "F.Fab")
			(hide yes)
			(effects
				(font
					(size 1.016 1.016)
					(thickness 0.1524)
				)
			)
		)
		(duplicate_pad_numbers_are_jumpers no)
		(fp_line
			(start 0.889 2.159)
			(end -0.889 2.159)
			(stroke
				(width 0.1524)
				(type default)
			)
			(layer "F.SilkS")
		)
		(fp_line
			(start 0.889 -1.9304)
			(end 0.889 2.159)
			(stroke
				(width 0.1524)
				(type default)
			)
			(layer "F.SilkS")
		)
		(fp_line
			(start 0.762 2.0574)
			(end -0.762 2.0574)
			(stroke
				(width 0.508)
				(type default)
			)
			(layer "F.SilkS")
		)
		(fp_line
			(start -0.889 2.159)
			(end -0.889 -1.9304)
			(stroke
				(width 0.1524)
				(type default)
			)
			(layer "F.SilkS")
		)
		(fp_line
			(start -0.889 -1.9304)
			(end 0.889 -1.9304)
			(stroke
				(width 0.1524)
				(type default)
			)
			(layer "F.SilkS")
		)
		(fp_rect
			(start -1.016 2.3114)
			(end 1.016 -2.0066)
			(stroke
				(width 0)
				(type default)
			)
			(fill no)
			(layer "F.CrtYd")
		)
		(fp_poly
			(pts
				(xy -1.016 -2.0066) (xy 1.016 -2.0066) (xy 1.016 2.3114) (xy -1.016 2.3114)
			)
			(stroke
				(width 0)
				(type default)
			)
			(fill no)
			(layer "F.Fab")
		)
		(pad "A" smd rect
			(at 0 -1.143 180)
			(size 0.5588 1.016)
			(layers "F.Cu" "F.Mask" "F.Paste")
			(net "SW_HDD_R1")
		)
		(pad "K" smd rect
			(at 0 1.143 180)
			(size 0.5588 1.016)
			(layers "F.Cu" "F.Mask" "F.Paste")
			(net "SW_HDD_N1")
		)
	)
)
